(kicad_pcb
	(version 20260206)
	(generator "pcbnew")
	(generator_version "10.0")
	(general
		(thickness 1.6)
		(legacy_teardrops no)
	)
	(paper "A4")
	(title_block
		(title "01162023_DA0F0TEBIF0_F0T_Expander_BD_F_brd_V02_OCP.brd")
		(comment 1 "Grand Teton / footprint 5622 of 9728 (PEX2), pads 2120-2237 of 2397")
	)
	(layers
		(0 "F.Cu" signal "TOP")
		(4 "In1.Cu" signal "GND")
		(6 "In2.Cu" signal "VCC")
		(8 "In3.Cu" signal "VCC1")
		(10 "In4.Cu" signal "GND1")
		(12 "In5.Cu" signal "IN1")
		(14 "In6.Cu" signal "GND2")
		(16 "In7.Cu" signal "IN2")
		(18 "In8.Cu" signal "GND3")
		(20 "In9.Cu" signal "IN3")
		(22 "In10.Cu" signal "GND4")
		(24 "In11.Cu" signal "IN4")
		(26 "In12.Cu" signal "GND5")
		(28 "In13.Cu" signal "IN5")
		(30 "In14.Cu" signal "GND6")
		(32 "In15.Cu" signal "IN6")
		(34 "In16.Cu" signal "GND7")
		(2 "B.Cu" signal "BOTTOM")
		(9 "F.Adhes" user "F.Adhesive")
		(11 "B.Adhes" user "B.Adhesive")
		(13 "F.Paste" user "Package Geometry/Pastemask Top")
		(15 "B.Paste" user "Package Geometry/Pastemask Bottom")
		(5 "F.SilkS" user "Ref Des/Silkscreen Top")
		(7 "B.SilkS" user "Ref Des/Silkscreen Bottom")
		(1 "F.Mask" user "Board Geometry/Soldermask Top")
		(3 "B.Mask" user "Board Geometry/Soldermask Bottom")
		(17 "Dwgs.User" user "User.Drawings")
		(19 "Cmts.User" user "User.Comments")
		(21 "Eco1.User" user "User.Eco1")
		(23 "Eco2.User" user "User.Eco2")
		(25 "Edge.Cuts" user "Board Geometry/Outline")
		(27 "Margin" user)
		(31 "F.CrtYd" user "Package Geometry/Place Bound Top")
		(29 "B.CrtYd" user "Package Geometry/Place Bound Bottom")
		(35 "F.Fab" user "Ref Des/Assembly Top")
		(33 "B.Fab" user "Ref Des/Assembly Bottom")
	)
	(footprint ""
		(layer "F.Cu")
		(at 291.84981 -295.89984)
		(property "Reference" "PEX2"
			(at -3.35153 35.56762 0)
			(unlocked yes)
			(layer "F.SilkS")
			(effects
				(font
					(size 2.032 1.524)
					(thickness 0.1524)
				)
				(justify left)
			)
		)
		(property "Value" ""
			(at 0 0 0)
			(layer "F.Fab")
			(effects
				(font
					(size 1.27 1.27)
				)
			)
		)
		(duplicate_pad_numbers_are_jumpers no)
		(pad "R17" smd circle
			(at -7.599934 -9.500108)
			(size 0.4572 0.4572)
			(layers "F.Cu" "F.Mask" "F.Paste")
			(net "GND")
		)
		(pad "R18" smd circle
			(at -6.649974 -9.500108)
			(size 0.4572 0.4572)
			(layers "F.Cu" "F.Mask" "F.Paste")
			(net "GND")
		)
		(pad "R19" smd circle
			(at -5.700014 -9.500108)
			(size 0.4572 0.4572)
			(layers "F.Cu" "F.Mask" "F.Paste")
			(net "GND")
		)
		(pad "R20" smd circle
			(at -4.750054 -9.500108)
			(size 0.4572 0.4572)
			(layers "F.Cu" "F.Mask" "F.Paste")
			(net "GND")
		)
		(pad "R21" smd circle
			(at -3.800094 -9.500108)
			(size 0.4572 0.4572)
			(layers "F.Cu" "F.Mask" "F.Paste")
			(net "GND")
		)
		(pad "R22" smd circle
			(at -2.84988 -9.500108)
			(size 0.4572 0.4572)
			(layers "F.Cu" "F.Mask" "F.Paste")
			(net "GND")
		)
		(pad "R23" smd circle
			(at -1.89992 -9.500108)
			(size 0.4572 0.4572)
			(layers "F.Cu" "F.Mask" "F.Paste")
			(net "GND")
		)
		(pad "R24" smd circle
			(at -0.94996 -9.500108)
			(size 0.4572 0.4572)
			(layers "F.Cu" "F.Mask" "F.Paste")
			(net "GND")
		)
		(pad "R25" smd circle
			(at 0 -9.500108)
			(size 0.4572 0.4572)
			(layers "F.Cu" "F.Mask" "F.Paste")
			(net "GND")
		)
		(pad "R26" smd circle
			(at 0.94996 -9.500108)
			(size 0.4572 0.4572)
			(layers "F.Cu" "F.Mask" "F.Paste")
			(net "GND")
		)
		(pad "R27" smd circle
			(at 1.89992 -9.500108)
			(size 0.4572 0.4572)
			(layers "F.Cu" "F.Mask" "F.Paste")
			(net "GND")
		)
		(pad "R28" smd circle
			(at 2.84988 -9.500108)
			(size 0.4572 0.4572)
			(layers "F.Cu" "F.Mask" "F.Paste")
			(net "GND")
		)
		(pad "R29" smd circle
			(at 3.800094 -9.500108)
			(size 0.4572 0.4572)
			(layers "F.Cu" "F.Mask" "F.Paste")
			(net "GND")
		)
		(pad "R30" smd circle
			(at 4.750054 -9.500108)
			(size 0.4572 0.4572)
			(layers "F.Cu" "F.Mask" "F.Paste")
			(net "GND")
		)
		(pad "R31" smd circle
			(at 5.700014 -9.500108)
			(size 0.4572 0.4572)
			(layers "F.Cu" "F.Mask" "F.Paste")
			(net "GND")
		)
		(pad "R32" smd circle
			(at 6.649974 -9.500108)
			(size 0.4572 0.4572)
			(layers "F.Cu" "F.Mask" "F.Paste")
			(net "GND")
		)
		(pad "R33" smd circle
			(at 7.599934 -9.500108)
			(size 0.4572 0.4572)
			(layers "F.Cu" "F.Mask" "F.Paste")
			(net "GND")
		)
		(pad "R34" smd circle
			(at 8.549894 -9.500108)
			(size 0.4572 0.4572)
			(layers "F.Cu" "F.Mask" "F.Paste")
			(net "GND")
		)
		(pad "R35" smd circle
			(at 9.500108 -9.500108)
			(size 0.4572 0.4572)
			(layers "F.Cu" "F.Mask" "F.Paste")
			(net "GND")
		)
		(pad "R36" smd circle
			(at 10.450068 -9.500108)
			(size 0.4572 0.4572)
			(layers "F.Cu" "F.Mask" "F.Paste")
			(net "Net_513")
		)
		(pad "R37" smd circle
			(at 11.400028 -9.500108)
			(size 0.4572 0.4572)
			(layers "F.Cu" "F.Mask" "F.Paste")
			(net "GND")
		)
		(pad "R38" smd circle
			(at 12.349988 -9.500108)
			(size 0.4572 0.4572)
			(layers "F.Cu" "F.Mask" "F.Paste")
			(net "Net_5318")
		)
		(pad "R39" smd circle
			(at 13.299948 -9.500108)
			(size 0.4572 0.4572)
			(layers "F.Cu" "F.Mask" "F.Paste")
			(net "Net_5312")
		)
		(pad "R40" smd circle
			(at 14.249908 -9.500108)
			(size 0.4572 0.4572)
			(layers "F.Cu" "F.Mask" "F.Paste")
			(net "GND")
		)
		(pad "R41" smd circle
			(at 15.200122 -9.500108)
			(size 0.4572 0.4572)
			(layers "F.Cu" "F.Mask" "F.Paste")
			(net "GND")
		)
		(pad "R42" smd circle
			(at 16.150082 -9.500108)
			(size 0.4572 0.4572)
			(layers "F.Cu" "F.Mask" "F.Paste")
			(net "GND")
		)
		(pad "R43" smd circle
			(at 17.100042 -9.500108)
			(size 0.4572 0.4572)
			(layers "F.Cu" "F.Mask" "F.Paste")
			(net "P5E_PEX2_STN4_TX_DP<65>")
		)
		(pad "R44" smd circle
			(at 18.050002 -9.500108)
			(size 0.4572 0.4572)
			(layers "F.Cu" "F.Mask" "F.Paste")
			(net "P5E_PEX2_STN4_TX_DN<65>")
		)
		(pad "R45" smd circle
			(at 18.999962 -9.500108)
			(size 0.4572 0.4572)
			(layers "F.Cu" "F.Mask" "F.Paste")
			(net "GND")
		)
		(pad "R46" smd circle
			(at 19.949922 -9.500108)
			(size 0.4572 0.4572)
			(layers "F.Cu" "F.Mask" "F.Paste")
			(net "P5E_PEX2_STN4_RX_DP<65>")
		)
		(pad "R47" smd circle
			(at 20.899882 -9.500108)
			(size 0.4572 0.4572)
			(layers "F.Cu" "F.Mask" "F.Paste")
			(net "P5E_PEX2_STN4_RX_DN<65>")
		)
		(pad "R48" smd circle
			(at 21.850096 -9.500108)
			(size 0.4572 0.4572)
			(layers "F.Cu" "F.Mask" "F.Paste")
			(net "GND")
		)
		(pad "R49" smd circle
			(at 22.800056 -9.500108)
			(size 0.4572 0.4572)
			(layers "F.Cu" "F.Mask" "F.Paste")
			(net "GND")
		)
		(pad "T1" smd circle
			(at -22.800056 -8.549894)
			(size 0.4572 0.4572)
			(layers "F.Cu" "F.Mask" "F.Paste")
			(net "P5E_PEX2_STN7_RX_DN<115>")
		)
		(pad "T2" smd circle
			(at -21.850096 -8.549894)
			(size 0.4572 0.4572)
			(layers "F.Cu" "F.Mask" "F.Paste")
			(net "P5E_PEX2_STN7_RX_DP<115>")
		)
		(pad "T3" smd circle
			(at -20.899882 -8.549894)
			(size 0.4572 0.4572)
			(layers "F.Cu" "F.Mask" "F.Paste")
			(net "GND")
		)
		(pad "T4" smd circle
			(at -19.949922 -8.549894)
			(size 0.4572 0.4572)
			(layers "F.Cu" "F.Mask" "F.Paste")
			(net "GND")
		)
		(pad "T5" smd circle
			(at -18.999962 -8.549894)
			(size 0.4572 0.4572)
			(layers "F.Cu" "F.Mask" "F.Paste")
			(net "GND")
		)
		(pad "T6" smd circle
			(at -18.050002 -8.549894)
			(size 0.4572 0.4572)
			(layers "F.Cu" "F.Mask" "F.Paste")
			(net "GND")
		)
		(pad "T7" smd circle
			(at -17.100042 -8.549894)
			(size 0.4572 0.4572)
			(layers "F.Cu" "F.Mask" "F.Paste")
			(net "GND")
		)
		(pad "T8" smd circle
			(at -16.150082 -8.549894)
			(size 0.4572 0.4572)
			(layers "F.Cu" "F.Mask" "F.Paste")
			(net "P5E_PEX2_STN7_TX_DN<115>")
		)
		(pad "T9" smd circle
			(at -15.200122 -8.549894)
			(size 0.4572 0.4572)
			(layers "F.Cu" "F.Mask" "F.Paste")
			(net "P5E_PEX2_STN7_TX_DP<115>")
		)
		(pad "T10" smd circle
			(at -14.249908 -8.549894)
			(size 0.4572 0.4572)
			(layers "F.Cu" "F.Mask" "F.Paste")
			(net "GND")
		)
		(pad "T11" smd circle
			(at -13.299948 -8.549894)
			(size 0.4572 0.4572)
			(layers "F.Cu" "F.Mask" "F.Paste")
			(net "GND")
		)
		(pad "T12" smd circle
			(at -12.349988 -8.549894)
			(size 0.4572 0.4572)
			(layers "F.Cu" "F.Mask" "F.Paste")
			(net "GND")
		)
		(pad "T13" smd circle
			(at -11.400028 -8.549894)
			(size 0.4572 0.4572)
			(layers "F.Cu" "F.Mask" "F.Paste")
			(net "GND")
		)
		(pad "T14" smd circle
			(at -10.450068 -8.549894)
			(size 0.4572 0.4572)
			(layers "F.Cu" "F.Mask" "F.Paste")
			(net "Net_520")
		)
		(pad "T15" smd circle
			(at -9.500108 -8.549894)
			(size 0.4572 0.4572)
			(layers "F.Cu" "F.Mask" "F.Paste")
			(net "GND")
		)
		(pad "T16" smd circle
			(at -8.549894 -8.549894)
			(size 0.4572 0.4572)
			(layers "F.Cu" "F.Mask" "F.Paste")
			(net "P1V25_SERDES_VDDPLL_PEX2")
		)
		(pad "T17" smd circle
			(at -7.599934 -8.549894)
			(size 0.4572 0.4572)
			(layers "F.Cu" "F.Mask" "F.Paste")
			(net "P1V25_SERDES_VDDPLL_PEX2")
		)
		(pad "T18" smd circle
			(at -6.649974 -8.549894)
			(size 0.4572 0.4572)
			(layers "F.Cu" "F.Mask" "F.Paste")
			(net "P1V25_SERDES_VDDPLL_PEX2")
		)
		(pad "T19" smd circle
			(at -5.700014 -8.549894)
			(size 0.4572 0.4572)
			(layers "F.Cu" "F.Mask" "F.Paste")
			(net "P1V25_SERDES_VDDPLL_PEX2")
		)
		(pad "T20" smd circle
			(at -4.750054 -8.549894)
			(size 0.4572 0.4572)
			(layers "F.Cu" "F.Mask" "F.Paste")
			(net "P1V25_SERDES_VDDPLL_PEX2")
		)
		(pad "T21" smd circle
			(at -3.800094 -8.549894)
			(size 0.4572 0.4572)
			(layers "F.Cu" "F.Mask" "F.Paste")
			(net "P1V25_SERDES_VDDPLL_PEX2")
		)
		(pad "T22" smd circle
			(at -2.84988 -8.549894)
			(size 0.4572 0.4572)
			(layers "F.Cu" "F.Mask" "F.Paste")
			(net "P1V25_SERDES_VDDPLL_PEX2")
		)
		(pad "T23" smd circle
			(at -1.89992 -8.549894)
			(size 0.4572 0.4572)
			(layers "F.Cu" "F.Mask" "F.Paste")
			(net "P1V25_SERDES_VDDPLL_PEX2")
		)
		(pad "T24" smd circle
			(at -0.94996 -8.549894)
			(size 0.4572 0.4572)
			(layers "F.Cu" "F.Mask" "F.Paste")
			(net "P1V25_SERDES_VDDPLL_PEX2")
		)
		(pad "T25" smd circle
			(at 0 -8.549894)
			(size 0.4572 0.4572)
			(layers "F.Cu" "F.Mask" "F.Paste")
			(net "P1V25_SERDES_VDDPLL_PEX2")
		)
		(pad "T26" smd circle
			(at 0.94996 -8.549894)
			(size 0.4572 0.4572)
			(layers "F.Cu" "F.Mask" "F.Paste")
			(net "P1V25_SERDES_VDDPLL_PEX2")
		)
		(pad "T27" smd circle
			(at 1.89992 -8.549894)
			(size 0.4572 0.4572)
			(layers "F.Cu" "F.Mask" "F.Paste")
			(net "P1V25_SERDES_VDDPLL_PEX2")
		)
		(pad "T28" smd circle
			(at 2.84988 -8.549894)
			(size 0.4572 0.4572)
			(layers "F.Cu" "F.Mask" "F.Paste")
			(net "P1V25_SERDES_VDDPLL_PEX2")
		)
		(pad "T29" smd circle
			(at 3.800094 -8.549894)
			(size 0.4572 0.4572)
			(layers "F.Cu" "F.Mask" "F.Paste")
			(net "P1V25_SERDES_VDDPLL_PEX2")
		)
		(pad "T30" smd circle
			(at 4.750054 -8.549894)
			(size 0.4572 0.4572)
			(layers "F.Cu" "F.Mask" "F.Paste")
			(net "P1V25_SERDES_VDDPLL_PEX2")
		)
		(pad "T31" smd circle
			(at 5.700014 -8.549894)
			(size 0.4572 0.4572)
			(layers "F.Cu" "F.Mask" "F.Paste")
			(net "P1V25_SERDES_VDDPLL_PEX2")
		)
		(pad "T32" smd circle
			(at 6.649974 -8.549894)
			(size 0.4572 0.4572)
			(layers "F.Cu" "F.Mask" "F.Paste")
			(net "P1V25_SERDES_VDDPLL_PEX2")
		)
		(pad "T33" smd circle
			(at 7.599934 -8.549894)
			(size 0.4572 0.4572)
			(layers "F.Cu" "F.Mask" "F.Paste")
			(net "P1V25_SERDES_VDDPLL_PEX2")
		)
		(pad "T34" smd circle
			(at 8.549894 -8.549894)
			(size 0.4572 0.4572)
			(layers "F.Cu" "F.Mask" "F.Paste")
			(net "GND")
		)
		(pad "T35" smd circle
			(at 9.500108 -8.549894)
			(size 0.4572 0.4572)
			(layers "F.Cu" "F.Mask" "F.Paste")
			(net "P1V8_VDDA_PEX2")
		)
		(pad "T36" smd circle
			(at 10.450068 -8.549894)
			(size 0.4572 0.4572)
			(layers "F.Cu" "F.Mask" "F.Paste")
			(net "Net_522")
		)
		(pad "T37" smd circle
			(at 11.400028 -8.549894)
			(size 0.4572 0.4572)
			(layers "F.Cu" "F.Mask" "F.Paste")
			(net "GND")
		)
		(pad "T38" smd circle
			(at 12.349988 -8.549894)
			(size 0.4572 0.4572)
			(layers "F.Cu" "F.Mask" "F.Paste")
			(net "RST_PEX2_S0_PERST_R_N")
		)
		(pad "T39" smd circle
			(at 13.299948 -8.549894)
			(size 0.4572 0.4572)
			(layers "F.Cu" "F.Mask" "F.Paste")
			(net "Net_380")
		)
		(pad "T40" smd circle
			(at 14.249908 -8.549894)
			(size 0.4572 0.4572)
			(layers "F.Cu" "F.Mask" "F.Paste")
			(net "GND")
		)
		(pad "T41" smd circle
			(at 15.200122 -8.549894)
			(size 0.4572 0.4572)
			(layers "F.Cu" "F.Mask" "F.Paste")
			(net "P5E_PEX2_STN4_TX_DP<64>")
		)
		(pad "T42" smd circle
			(at 16.150082 -8.549894)
			(size 0.4572 0.4572)
			(layers "F.Cu" "F.Mask" "F.Paste")
			(net "P5E_PEX2_STN4_TX_DN<64>")
		)
		(pad "T43" smd circle
			(at 17.100042 -8.549894)
			(size 0.4572 0.4572)
			(layers "F.Cu" "F.Mask" "F.Paste")
			(net "GND")
		)
		(pad "T44" smd circle
			(at 18.050002 -8.549894)
			(size 0.4572 0.4572)
			(layers "F.Cu" "F.Mask" "F.Paste")
			(net "GND")
		)
		(pad "T45" smd circle
			(at 18.999962 -8.549894)
			(size 0.4572 0.4572)
			(layers "F.Cu" "F.Mask" "F.Paste")
			(net "GND")
		)
		(pad "T46" smd circle
			(at 19.949922 -8.549894)
			(size 0.4572 0.4572)
			(layers "F.Cu" "F.Mask" "F.Paste")
			(net "GND")
		)
		(pad "T47" smd circle
			(at 20.899882 -8.549894)
			(size 0.4572 0.4572)
			(layers "F.Cu" "F.Mask" "F.Paste")
			(net "GND")
		)
		(pad "T48" smd circle
			(at 21.850096 -8.549894)
			(size 0.4572 0.4572)
			(layers "F.Cu" "F.Mask" "F.Paste")
			(net "P5E_PEX2_STN4_RX_DP<64>")
		)
		(pad "T49" smd circle
			(at 22.800056 -8.549894)
			(size 0.4572 0.4572)
			(layers "F.Cu" "F.Mask" "F.Paste")
			(net "P5E_PEX2_STN4_RX_DN<64>")
		)
		(pad "U1" smd circle
			(at -22.800056 -7.599934)
			(size 0.4572 0.4572)
			(layers "F.Cu" "F.Mask" "F.Paste")
			(net "GND")
		)
		(pad "U2" smd circle
			(at -21.850096 -7.599934)
			(size 0.4572 0.4572)
			(layers "F.Cu" "F.Mask" "F.Paste")
			(net "GND")
		)
		(pad "U3" smd circle
			(at -20.899882 -7.599934)
			(size 0.4572 0.4572)
			(layers "F.Cu" "F.Mask" "F.Paste")
			(net "P5E_PEX2_STN7_RX_DN<114>")
		)
		(pad "U4" smd circle
			(at -19.949922 -7.599934)
			(size 0.4572 0.4572)
			(layers "F.Cu" "F.Mask" "F.Paste")
			(net "P5E_PEX2_STN7_RX_DP<114>")
		)
		(pad "U5" smd circle
			(at -18.999962 -7.599934)
			(size 0.4572 0.4572)
			(layers "F.Cu" "F.Mask" "F.Paste")
			(net "GND")
		)
		(pad "U6" smd circle
			(at -18.050002 -7.599934)
			(size 0.4572 0.4572)
			(layers "F.Cu" "F.Mask" "F.Paste")
			(net "P5E_PEX2_STN7_TX_DN<114>")
		)
		(pad "U7" smd circle
			(at -17.100042 -7.599934)
			(size 0.4572 0.4572)
			(layers "F.Cu" "F.Mask" "F.Paste")
			(net "P5E_PEX2_STN7_TX_DP<114>")
		)
		(pad "U8" smd circle
			(at -16.150082 -7.599934)
			(size 0.4572 0.4572)
			(layers "F.Cu" "F.Mask" "F.Paste")
			(net "GND")
		)
		(pad "U9" smd circle
			(at -15.200122 -7.599934)
			(size 0.4572 0.4572)
			(layers "F.Cu" "F.Mask" "F.Paste")
			(net "GND")
		)
		(pad "U10" smd circle
			(at -14.249908 -7.599934)
			(size 0.4572 0.4572)
			(layers "F.Cu" "F.Mask" "F.Paste")
			(net "GND")
		)
		(pad "U11" smd circle
			(at -13.299948 -7.599934)
			(size 0.4572 0.4572)
			(layers "F.Cu" "F.Mask" "F.Paste")
			(net "GND")
		)
		(pad "U12" smd circle
			(at -12.349988 -7.599934)
			(size 0.4572 0.4572)
			(layers "F.Cu" "F.Mask" "F.Paste")
			(net "GND")
		)
		(pad "U13" smd circle
			(at -11.400028 -7.599934)
			(size 0.4572 0.4572)
			(layers "F.Cu" "F.Mask" "F.Paste")
			(net "GND")
		)
		(pad "U14" smd circle
			(at -10.450068 -7.599934)
			(size 0.4572 0.4572)
			(layers "F.Cu" "F.Mask" "F.Paste")
			(net "Net_526")
		)
		(pad "U15" smd circle
			(at -9.500108 -7.599934)
			(size 0.4572 0.4572)
			(layers "F.Cu" "F.Mask" "F.Paste")
			(net "GND")
		)
		(pad "U16" smd circle
			(at -8.549894 -7.599934)
			(size 0.4572 0.4572)
			(layers "F.Cu" "F.Mask" "F.Paste")
			(net "GND")
		)
		(pad "U17" smd circle
			(at -7.599934 -7.599934)
			(size 0.4572 0.4572)
			(layers "F.Cu" "F.Mask" "F.Paste")
			(net "GND")
		)
		(pad "U18" smd circle
			(at -6.649974 -7.599934)
			(size 0.4572 0.4572)
			(layers "F.Cu" "F.Mask" "F.Paste")
			(net "GND")
		)
		(pad "U19" smd circle
			(at -5.700014 -7.599934)
			(size 0.4572 0.4572)
			(layers "F.Cu" "F.Mask" "F.Paste")
			(net "GND")
		)
		(pad "U20" smd circle
			(at -4.750054 -7.599934)
			(size 0.4572 0.4572)
			(layers "F.Cu" "F.Mask" "F.Paste")
			(net "GND")
		)
		(pad "U21" smd circle
			(at -3.800094 -7.599934)
			(size 0.4572 0.4572)
			(layers "F.Cu" "F.Mask" "F.Paste")
			(net "GND")
		)
		(pad "U22" smd circle
			(at -2.84988 -7.599934)
			(size 0.4572 0.4572)
			(layers "F.Cu" "F.Mask" "F.Paste")
			(net "GND")
		)
		(pad "U23" smd circle
			(at -1.89992 -7.599934)
			(size 0.4572 0.4572)
			(layers "F.Cu" "F.Mask" "F.Paste")
			(net "GND")
		)
		(pad "U24" smd circle
			(at -0.94996 -7.599934)
			(size 0.4572 0.4572)
			(layers "F.Cu" "F.Mask" "F.Paste")
			(net "GND")
		)
		(pad "U25" smd circle
			(at 0 -7.599934)
			(size 0.4572 0.4572)
			(layers "F.Cu" "F.Mask" "F.Paste")
			(net "GND")
		)
		(pad "U26" smd circle
			(at 0.94996 -7.599934)
			(size 0.4572 0.4572)
			(layers "F.Cu" "F.Mask" "F.Paste")
			(net "GND")
		)
		(pad "U27" smd circle
			(at 1.89992 -7.599934)
			(size 0.4572 0.4572)
			(layers "F.Cu" "F.Mask" "F.Paste")
			(net "GND")
		)
		(pad "U28" smd circle
			(at 2.84988 -7.599934)
			(size 0.4572 0.4572)
			(layers "F.Cu" "F.Mask" "F.Paste")
			(net "GND")
		)
		(pad "U29" smd circle
			(at 3.800094 -7.599934)
			(size 0.4572 0.4572)
			(layers "F.Cu" "F.Mask" "F.Paste")
			(net "GND")
		)
		(pad "U30" smd circle
			(at 4.750054 -7.599934)
			(size 0.4572 0.4572)
			(layers "F.Cu" "F.Mask" "F.Paste")
			(net "GND")
		)
		(pad "U31" smd circle
			(at 5.700014 -7.599934)
			(size 0.4572 0.4572)
			(layers "F.Cu" "F.Mask" "F.Paste")
			(net "GND")
		)
		(pad "U32" smd circle
			(at 6.649974 -7.599934)
			(size 0.4572 0.4572)
			(layers "F.Cu" "F.Mask" "F.Paste")
			(net "GND")
		)
		(pad "U33" smd circle
			(at 7.599934 -7.599934)
			(size 0.4572 0.4572)
			(layers "F.Cu" "F.Mask" "F.Paste")
			(net "GND")
		)
		(pad "U34" smd circle
			(at 8.549894 -7.599934)
			(size 0.4572 0.4572)
			(layers "F.Cu" "F.Mask" "F.Paste")
			(net "GND")
		)
		(pad "U35" smd circle
			(at 9.500108 -7.599934)
			(size 0.4572 0.4572)
			(layers "F.Cu" "F.Mask" "F.Paste")
			(net "GND")
		)
		(pad "U36" smd circle
			(at 10.450068 -7.599934)
			(size 0.4572 0.4572)
			(layers "F.Cu" "F.Mask" "F.Paste")
			(net "Net_523")
		)
	)
)
